# LPDDR5 Testbed — KiCad project settings (.kicad_pro: net classes, design rules, text variables)
{
  "board": {
    "3dviewports": [],
    "design_settings": {
      "defaults": {
        "apply_defaults_to_fp_fields": false,
        "apply_defaults_to_fp_shapes": false,
        "apply_defaults_to_fp_text": false,
        "board_outline_line_width": 0.05,
        "copper_line_width": 0.2,
        "copper_text_italic": false,
        "copper_text_size_h": 1.5,
        "copper_text_size_v": 1.5,
        "copper_text_thickness": 0.3,
        "copper_text_upright": false,
        "courtyard_line_width": 0.05,
        "dimension_precision": 4,
        "dimension_units": 3,
        "dimensions": {
          "arrow_length": 1270000,
          "extension_offset": 500000,
          "keep_text_aligned": true,
          "suppress_zeroes": false,
          "text_position": 0,
          "units_format": 1
        },
        "fab_line_width": 0.1,
        "fab_text_italic": false,
        "fab_text_size_h": 1.0,
        "fab_text_size_v": 1.0,
        "fab_text_thickness": 0.15,
        "fab_text_upright": false,
        "other_line_width": 0.1,
        "other_text_italic": false,
        "other_text_size_h": 1.0,
        "other_text_size_v": 1.0,
        "other_text_thickness": 0.15,
        "other_text_upright": false,
        "pads": {
          "drill": 0.762,
          "height": 1.524,
          "width": 1.524
        },
        "silk_line_width": 0.12,
        "silk_text_italic": false,
        "silk_text_size_h": 1.0,
        "silk_text_size_v": 1.0,
        "silk_text_thickness": 0.15,
        "silk_text_upright": false,
        "zones": {
          "45_degree_only": false,
          "min_clearance": 0.508
        }
      },
      "diff_pair_dimensions": [
        {
          "gap": 0.0,
          "via_gap": 0.0,
          "width": 0.0
        }
      ],
      "drc_exclusions": [],
      "meta": {
        "version": 2
      },
      "rule_severities": {
        "annular_width": "error",
        "clearance": "error",
        "connection_width": "warning",
        "copper_edge_clearance": "error",
        "copper_sliver": "warning",
        "courtyards_overlap": "error",
        "creepage": "error",
        "diff_pair_gap_out_of_range": "error",
        "diff_pair_uncoupled_length_too_long": "error",
        "drill_out_of_range": "error",
        "duplicate_footprints": "warning",
        "extra_footprint": "warning",
        "footprint": "error",
        "footprint_filters_mismatch": "ignore",
        "footprint_symbol_mismatch": "warning",
        "footprint_type_mismatch": "error",
        "hole_clearance": "error",
        "hole_near_hole": "error",
        "hole_to_hole": "error",
        "holes_co_located": "warning",
        "invalid_outline": "error",
        "isolated_copper": "warning",
        "item_on_disabled_layer": "error",
        "items_not_allowed": "error",
        "length_out_of_range": "error",
        "lib_footprint_issues": "warning",
        "lib_footprint_mismatch": "warning",
        "malformed_courtyard": "error",
        "microvia_drill_out_of_range": "error",
        "mirrored_text_on_front_layer": "warning",
        "missing_courtyard": "ignore",
        "missing_footprint": "warning",
        "net_conflict": "warning",
        "nonmirrored_text_on_back_layer": "warning",
        "npth_inside_courtyard": "ignore",
        "padstack": "error",
        "pth_inside_courtyard": "ignore",
        "shorting_items": "error",
        "silk_edge_clearance": "warning",
        "silk_over_copper": "warning",
        "silk_overlap": "warning",
        "skew_out_of_range": "error",
        "solder_mask_bridge": "error",
        "starved_thermal": "error",
        "text_height": "warning",
        "text_on_edge_cuts": "error",
        "text_thickness": "warning",
        "through_hole_pad_without_hole": "error",
        "too_many_vias": "error",
        "track_angle": "error",
        "track_dangling": "warning",
        "track_segment_length": "error",
        "track_width": "error",
        "tracks_crossing": "error",
        "unconnected_items": "error",
        "unresolved_variable": "error",
        "via_dangling": "warning",
        "zone_has_empty_net": "error",
        "zones_intersect": "error"
      },
      "rules": {
        "allow_blind_buried_vias": false,
        "allow_microvias": false,
        "max_error": 0.005,
        "min_clearance": 0.09,
        "min_connection": 0.0,
        "min_copper_edge_clearance": 0.01,
        "min_groove_width": 0.0,
        "min_hole_clearance": 0.2,
        "min_hole_to_hole": 0.25,
        "min_microvia_diameter": 0.2,
        "min_microvia_drill": 0.1,
        "min_resolved_spokes": 2,
        "min_silk_clearance": 0.0,
        "min_text_height": 0.8,
        "min_text_thickness": 0.08,
        "min_through_hole_diameter": 0.15,
        "min_track_width": 0.09,
        "min_via_annular_width": 0.1,
        "min_via_diameter": 0.4,
        "solder_mask_to_copper_clearance": 0.0,
        "use_height_for_length_calcs": true
      },
      "teardrop_options": [
        {
          "td_onpthpad": true,
          "td_onroundshapesonly": false,
          "td_onsmdpad": true,
          "td_ontrackend": false,
          "td_onvia": true
        }
      ],
      "teardrop_parameters": [
        {
          "td_allow_use_two_tracks": true,
          "td_curve_segcount": 0,
          "td_height_ratio": 1.0,
          "td_length_ratio": 0.5,
          "td_maxheight": 2.0,
          "td_maxlen": 1.0,
          "td_on_pad_in_zone": false,
          "td_target_name": "td_round_shape",
          "td_width_to_size_filter_ratio": 0.9
        },
        {
          "td_allow_use_two_tracks": true,
          "td_curve_segcount": 0,
          "td_height_ratio": 1.0,
          "td_length_ratio": 0.5,
          "td_maxheight": 2.0,
          "td_maxlen": 1.0,
          "td_on_pad_in_zone": false,
          "td_target_name": "td_rect_shape",
          "td_width_to_size_filter_ratio": 0.9
        },
        {
          "td_allow_use_two_tracks": true,
          "td_curve_segcount": 0,
          "td_height_ratio": 1.0,
          "td_length_ratio": 0.5,
          "td_maxheight": 2.0,
          "td_maxlen": 1.0,
          "td_on_pad_in_zone": false,
          "td_target_name": "td_track_end",
          "td_width_to_size_filter_ratio": 0.9
        }
      ],
      "track_widths": [
        0.0
      ],
      "tuning_pattern_settings": {
        "diff_pair_defaults": {
          "corner_radius_percentage": 80,
          "corner_style": 1,
          "max_amplitude": 1.0,
          "min_amplitude": 0.2,
          "single_sided": false,
          "spacing": 1.0
        },
        "diff_pair_skew_defaults": {
          "corner_radius_percentage": 80,
          "corner_style": 1,
          "max_amplitude": 1.0,
          "min_amplitude": 0.2,
          "single_sided": false,
          "spacing": 0.6
        },
        "single_track_defaults": {
          "corner_radius_percentage": 80,
          "corner_style": 1,
          "max_amplitude": 1.0,
          "min_amplitude": 0.2,
          "single_sided": false,
          "spacing": 0.6
        }
      },
      "via_dimensions": [
        {
          "diameter": 0.0,
          "drill": 0.0
        }
      ],
      "zones_allow_external_fillets": false,
      "zones_use_no_outline": true
    },
    "ipc2581": {
      "dist": "",
      "distpn": "",
      "internal_id": "",
      "mfg": "",
      "mpn": ""
    },
    "layer_pairs": [],
    "layer_presets": [],
    "viewports": []
  },
  "boards": [],
  "cvpcb": {
    "equivalence_files": []
  },
  "erc": {
    "erc_exclusions": [],
    "meta": {
      "version": 0
    },
    "pin_map": [
      [
        0,
        0,
        0,
        0,
        0,
        0,
        1,
        0,
        0,
        0,
        0,
        2
      ],
      [
        0,
        2,
        0,
        1,
        0,
        0,
        1,
        0,
        2,
        2,
        2,
        2
      ],
      [
        0,
        0,
        0,
        0,
        0,
        0,
        1,
        0,
        1,
        0,
        1,
        2
      ],
      [
        0,
        1,
        0,
        0,
        0,
        0,
        1,
        1,
        2,
        1,
        1,
        2
      ],
      [
        0,
        0,
        0,
        0,
        0,
        0,
        1,
        0,
        0,
        0,
        0,
        2
      ],
      [
        0,
        0,
        0,
        0,
        0,
        0,
        0,
        0,
        0,
        0,
        0,
        2
      ],
      [
        1,
        1,
        1,
        1,
        1,
        0,
        1,
        1,
        1,
        1,
        1,
        2
      ],
      [
        0,
        0,
        0,
        1,
        0,
        0,
        1,
        0,
        0,
        0,
        0,
        2
      ],
      [
        0,
        2,
        1,
        2,
        0,
        0,
        1,
        0,
        2,
        2,
        2,
        2
      ],
      [
        0,
        2,
        0,
        1,
        0,
        0,
        1,
        0,
        2,
        0,
        0,
        2
      ],
      [
        0,
        2,
        1,
        1,
        0,
        0,
        1,
        0,
        2,
        0,
        0,
        2
      ],
      [
        2,
        2,
        2,
        2,
        2,
        2,
        2,
        2,
        2,
        2,
        2,
        2
      ]
    ],
    "rule_severities": {
      "bus_definition_conflict": "error",
      "bus_entry_needed": "error",
      "bus_label_syntax": "error",
      "bus_to_bus_conflict": "error",
      "bus_to_net_conflict": "error",
      "different_unit_footprint": "error",
      "different_unit_net": "error",
      "duplicate_reference": "error",
      "duplicate_sheet_names": "error",
      "endpoint_off_grid": "warning",
      "extra_units": "error",
      "footprint_filter": "ignore",
      "footprint_link_issues": "warning",
      "four_way_junction": "ignore",
      "global_label_dangling": "warning",
      "hier_label_mismatch": "error",
      "label_dangling": "error",
      "label_multiple_wires": "warning",
      "lib_symbol_issues": "warning",
      "lib_symbol_mismatch": "warning",
      "missing_bidi_pin": "warning",
      "missing_input_pin": "warning",
      "missing_power_pin": "error",
      "missing_unit": "warning",
      "multiple_net_names": "warning",
      "net_not_bus_member": "warning",
      "no_connect_connected": "warning",
      "no_connect_dangling": "warning",
      "pin_not_connected": "error",
      "pin_not_driven": "error",
      "pin_to_pin": "warning",
      "power_pin_not_driven": "error",
      "same_local_global_label": "warning",
      "similar_label_and_power": "warning",
      "similar_labels": "warning",
      "similar_power": "warning",
      "simulation_model_issue": "ignore",
      "single_global_label": "ignore",
      "unannotated": "error",
      "unconnected_wire_endpoint": "warning",
      "undefined_netclass": "error",
      "unit_value_mismatch": "error",
      "unresolved_variable": "error",
      "wire_dangling": "error"
    }
  },
  "libraries": {
    "pinned_footprint_libs": [],
    "pinned_symbol_libs": []
  },
  "meta": {
    "filename": "lpddr5-testbed.kicad_pro",
    "version": 3
  },
  "net_settings": {
    "classes": [
      {
        "bus_width": 12,
        "clearance": 0.09,
        "diff_pair_gap": 0.1,
        "diff_pair_via_gap": 0.25,
        "diff_pair_width": 0.1,
        "line_style": 0,
        "microvia_diameter": 0.3,
        "microvia_drill": 0.1,
        "name": "Default",
        "pcb_color": "rgba(0, 0, 0, 0.000)",
        "priority": 2147483647,
        "schematic_color": "rgba(0, 0, 0, 0.000)",
        "track_width": 0.15,
        "via_diameter": 0.4,
        "via_drill": 0.15,
        "wire_width": 6
      }
    ],
    "meta": {
      "version": 4
    },
    "net_colors": null,
    "netclass_assignments": null,
    "netclass_patterns": []
  },
  "pcbnew": {
    "last_paths": {
      "gencad": "",
      "idf": "",
      "netlist": "",
      "plot": "",
      "pos_files": "",
      "specctra_dsn": "",
      "step": "",
      "svg": "",
      "vrml": ""
    },
    "page_layout_descr_file": ""
  },
  "schematic": {
    "annotate_start_num": 0,
    "bom_export_filename": "${PROJECTNAME}.csv",
    "bom_fmt_presets": [],
    "bom_fmt_settings": {
      "field_delimiter": ",",
      "keep_line_breaks": false,
      "keep_tabs": false,
      "name": "CSV",
      "ref_delimiter": ",",
      "ref_range_delimiter": "",
      "string_delimiter": "\""
    },
    "bom_presets": [],
    "bom_settings": {
      "exclude_dnp": false,
      "fields_ordered": [
        {
          "group_by": false,
          "label": "Reference",
          "name": "Reference",
          "show": true
        },
        {
          "group_by": false,
          "label": "Qty",
          "name": "${QUANTITY}",
          "show": true
        },
        {
          "group_by": true,
          "label": "Value",
          "name": "Value",
          "show": true
        },
        {
          "group_by": true,
          "label": "DNP",
          "name": "${DNP}",
          "show": true
        },
        {
          "group_by": true,
          "label": "Exclude from BOM",
          "name": "${EXCLUDE_FROM_BOM}",
          "show": true
        },
        {
          "group_by": true,
          "label": "Exclude from Board",
          "name": "${EXCLUDE_FROM_BOARD}",
          "show": true
        },
        {
          "group_by": true,
          "label": "Footprint",
          "name": "Footprint",
          "show": true
        },
        {
          "group_by": false,
          "label": "Datasheet",
          "name": "Datasheet",
          "show": true
        }
      ],
      "filter_string": "",
      "group_symbols": true,
      "include_excluded_from_bom": true,
      "name": "Default Editing",
      "sort_asc": true,
      "sort_field": "Reference"
    },
    "connection_grid_size": 50.0,
    "drawing": {
      "dashed_lines_dash_length_ratio": 12.0,
      "dashed_lines_gap_length_ratio": 3.0,
      "default_line_thickness": 6.0,
      "default_text_size": 50.0,
      "field_names": [],
      "intersheets_ref_own_page": false,
      "intersheets_ref_prefix": "",
      "intersheets_ref_short": false,
      "intersheets_ref_show": false,
      "intersheets_ref_suffix": "",
      "junction_size_choice": 3,
      "label_size_ratio": 0.375,
      "operating_point_overlay_i_precision": 3,
      "operating_point_overlay_i_range": "~A",
      "operating_point_overlay_v_precision": 3,
      "operating_point_overlay_v_range": "~V",
      "overbar_offset_ratio": 1.23,
      "pin_symbol_size": 25.0,
      "text_offset_ratio": 0.15
    },
    "legacy_lib_dir": "",
    "legacy_lib_list": [],
    "meta": {
      "version": 1
    },
    "net_format_name": "",
    "ngspice": {
      "fix_include_paths": true,
      "fix_passive_vals": false,
      "meta": {
        "version": 0
      },
      "model_mode": 0,
      "workbook_filename": ""
    },
    "page_layout_descr_file": "",
    "plot_directory": "",
    "space_save_all_events": true,
    "spice_adjust_passive_values": false,
    "spice_current_sheet_as_root": false,
    "spice_external_command": "spice \"%I\"",
    "spice_model_current_sheet_as_root": true,
    "spice_save_all_currents": false,
    "spice_save_all_dissipations": false,
    "spice_save_all_voltages": false,
    "subpart_first_id": 65,
    "subpart_id_separator": 0
  },
  "sheets": [
    [
      "",
      "Root"
    ],
    [
      "",
      "Translators"
    ],
    [
      "",
      "SODIMM"
    ],
    [
      "",
      "LPDDR5"
    ],
    [
      "",
      "Power supply"
    ],
    [
      "",
      "Translators1"
    ]
  ],
  "text_variables": {}
}
